(kicad_pcb
	(version 20260206)
	(generator "pcbnew")
	(generator_version "10.0")
	(general
		(thickness 1.6)
		(legacy_teardrops no)
	)
	(paper "A4")
	(title_block
		(title "panther-plus-userver — 13130-1b_20150205.brd")
		(comment 1 "Honey Badger (Wiwynn) / footprints 500-504 of 1509")
	)
	(layers
		(0 "F.Cu" signal "TOP")
		(4 "In1.Cu" signal "L2")
		(6 "In2.Cu" signal "L3")
		(8 "In3.Cu" signal "L4")
		(10 "In4.Cu" signal "L5")
		(12 "In5.Cu" signal "L6")
		(14 "In6.Cu" signal "L7")
		(16 "In7.Cu" signal "L8")
		(18 "In8.Cu" signal "L9")
		(20 "In9.Cu" signal "L10")
		(22 "In10.Cu" signal "L11")
		(2 "B.Cu" signal "BOTTOM")
		(9 "F.Adhes" user "F.Adhesive")
		(11 "B.Adhes" user "B.Adhesive")
		(13 "F.Paste" user "Package Geometry/Pastemask Top")
		(15 "B.Paste" user "Package Geometry/Pastemask Bottom")
		(5 "F.SilkS" user "Ref Des/Silkscreen Top")
		(7 "B.SilkS" user "Ref Des/Silkscreen Bottom")
		(1 "F.Mask" user "Board Geometry/Soldermask Top")
		(3 "B.Mask" user "Board Geometry/Soldermask Bottom")
		(17 "Dwgs.User" user "User.Drawings")
		(19 "Cmts.User" user "User.Comments")
		(21 "Eco1.User" user "User.Eco1")
		(23 "Eco2.User" user "User.Eco2")
		(25 "Edge.Cuts" user "Board Geometry/Outline")
		(27 "Margin" user)
		(31 "F.CrtYd" user "Package Geometry/Place Bound Top")
		(29 "B.CrtYd" user "Package Geometry/Place Bound Bottom")
		(35 "F.Fab" user "Ref Des/Assembly Top")
		(33 "B.Fab" user "Ref Des/Assembly Bottom")
	)
	(footprint ""
		(layer "F.Cu")
		(at 34.9504 -54.9656)
		(property "Reference" "PC20"
			(at 0 0 0)
			(layer "F.SilkS")
			(hide yes)
			(effects
				(font
					(size 1.27 1.27)
				)
			)
		)
		(property "Value" "SC10U25V5KX-GP"
			(at 0 -4.9022 0)
			(unlocked yes)
			(layer "F.Fab")
			(hide yes)
			(effects
				(font
					(size 1.016 1.016)
					(thickness 0.1524)
				)
			)
		)
		(property "Device Type" "C805H56"
			(at 0 -6.8072 0)
			(unlocked yes)
			(layer "F.Fab")
			(hide yes)
			(effects
				(font
					(size 1.016 1.016)
					(thickness 0.1524)
				)
			)
		)
		(duplicate_pad_numbers_are_jumpers no)
		(fp_line
			(start 0.6096 0)
			(end -0.6096 0)
			(stroke
				(width 0.3048)
				(type default)
			)
			(layer "F.SilkS")
		)
		(fp_poly
			(pts
				(xy -0.9017 1.4351) (xy 0.9017 1.4351) (xy 0.9017 -1.4351) (xy -0.9017 -1.4351)
			)
			(stroke
				(width 0)
				(type default)
			)
			(fill no)
			(layer "F.CrtYd")
		)
		(fp_poly
			(pts
				(xy 0.9017 1.4351) (xy 0.9017 -1.4351) (xy -0.9017 -1.4351) (xy -0.9017 1.4351)
			)
			(stroke
				(width 0)
				(type default)
			)
			(fill no)
			(layer "F.Fab")
		)
		(pad "1" smd rect
			(at 0 -0.8382)
			(size 1.5494 0.9398)
			(layers "F.Cu" "F.Mask" "F.Paste")
			(net "VR_FET_SW_P12V_PVCCP_PVNN")
		)
		(pad "2" smd rect
			(at 0 0.8382)
			(size 1.5494 0.9398)
			(layers "F.Cu" "F.Mask" "F.Paste")
			(net "GND")
		)
	)
	(footprint ""
		(layer "F.Cu")
		(at 31.4198 -38.7604 180)
		(property "Reference" "R491"
			(at 0 0 180)
			(layer "F.SilkS")
			(hide yes)
			(effects
				(font
					(size 1.27 1.27)
				)
			)
		)
		(property "Value" "51R2F-2-GP"
			(at 1.7907 -1.1176 180)
			(unlocked yes)
			(layer "F.Fab")
			(hide yes)
			(effects
				(font
					(size 1.016 1.016)
					(thickness 0.1524)
				)
			)
		)
		(property "Device Type" "R402H16"
			(at 1.7907 -2.6416 180)
			(unlocked yes)
			(layer "F.Fab")
			(hide yes)
			(effects
				(font
					(size 1.016 1.016)
					(thickness 0.1524)
				)
			)
		)
		(duplicate_pad_numbers_are_jumpers no)
		(fp_rect
			(start -0.381 0.8382)
			(end 0.381 -0.8382)
			(stroke
				(width 0)
				(type default)
			)
			(fill no)
			(layer "F.CrtYd")
		)
		(fp_rect
			(start -0.381 0.8382)
			(end 0.381 -0.8382)
			(stroke
				(width 0)
				(type default)
			)
			(fill no)
			(layer "F.Fab")
		)
		(pad "1" smd custom
			(at 0 -0.4318 180)
			(size 0.127 0.127)
			(layers "F.Cu" "F.Mask" "F.Paste")
			(net "P1V0_STBY")
			(options
				(clearance outline)
				(anchor circle)
			)
			(primitives
				(gr_poly
					(pts
						(arc
							(start -0.2032 -0.2794)
							(mid -0.239121 -0.264521)
							(end -0.254 -0.2286)
						)
						(arc
							(start -0.254 0.2286)
							(mid -0.239121 0.264521)
							(end -0.2032 0.2794)
						)
						(arc
							(start 0.2032 0.2794)
							(mid 0.239121 0.264521)
							(end 0.254 0.2286)
						)
						(arc
							(start 0.254 -0.2286)
							(mid 0.239121 -0.264521)
							(end 0.2032 -0.2794)
						)
					)
					(width 0)
					(fill yes)
				)
			)
		)
		(pad "2" smd custom
			(at 0 0.4318 180)
			(size 0.127 0.127)
			(layers "F.Cu" "F.Mask" "F.Paste")
			(net "XDP_SOC_CPU_TCK")
			(options
				(clearance outline)
				(anchor circle)
			)
			(primitives
				(gr_poly
					(pts
						(arc
							(start -0.2032 -0.2794)
							(mid -0.239121 -0.264521)
							(end -0.254 -0.2286)
						)
						(arc
							(start -0.254 0.2286)
							(mid -0.239121 0.264521)
							(end -0.2032 0.2794)
						)
						(arc
							(start 0.2032 0.2794)
							(mid 0.239121 0.264521)
							(end 0.254 0.2286)
						)
						(arc
							(start 0.254 -0.2286)
							(mid 0.239121 -0.264521)
							(end 0.2032 -0.2794)
						)
					)
					(width 0)
					(fill yes)
				)
			)
		)
	)
	(footprint ""
		(layer "F.Cu")
		(at 23.368 -43.307 180)
		(property "Reference" "PC149"
			(at 0 0 180)
			(layer "F.SilkS")
			(hide yes)
			(effects
				(font
					(size 1.27 1.27)
				)
			)
		)
		(property "Value" "SC22U6D3V3MX-1-GP"
			(at -0.0254 -2.0193 180)
			(unlocked yes)
			(layer "F.Fab")
			(hide yes)
			(effects
				(font
					(size 1.016 1.016)
					(thickness 0.1524)
				)
			)
		)
		(property "Device Type" "C603H40"
			(at -0.0254 -3.5433 180)
			(unlocked yes)
			(layer "F.Fab")
			(hide yes)
			(effects
				(font
					(size 1.016 1.016)
					(thickness 0.1524)
				)
			)
		)
		(duplicate_pad_numbers_are_jumpers no)
		(fp_line
			(start -0.4064 0)
			(end 0.4064 0)
			(stroke
				(width 0.2286)
				(type default)
			)
			(layer "F.SilkS")
		)
		(fp_rect
			(start -0.635 1.1811)
			(end 0.635 -1.1811)
			(stroke
				(width 0)
				(type default)
			)
			(fill no)
			(layer "F.CrtYd")
		)
		(fp_rect
			(start -0.635 1.1811)
			(end 0.635 -1.1811)
			(stroke
				(width 0)
				(type default)
			)
			(fill no)
			(layer "F.Fab")
		)
		(pad "1" smd custom
			(at 0 -0.6604 180)
			(size 0.19685 0.19685)
			(layers "F.Cu" "F.Mask" "F.Paste")
			(net "P3V3_STBY_OUT")
			(options
				(clearance outline)
				(anchor circle)
			)
			(primitives
				(gr_poly
					(pts
						(arc
							(start 0.508 -0.2921)
							(mid 0.478242 -0.363942)
							(end 0.4064 -0.3937)
						)
						(arc
							(start -0.4064 -0.3937)
							(mid -0.478242 -0.363942)
							(end -0.508 -0.2921)
						)
						(arc
							(start -0.508 0.2921)
							(mid -0.478242 0.363942)
							(end -0.4064 0.3937)
						)
						(arc
							(start 0.4064 0.3937)
							(mid 0.478242 0.363942)
							(end 0.508 0.2921)
						)
					)
					(width 0)
					(fill yes)
				)
			)
		)
		(pad "2" smd custom
			(at 0 0.6604 180)
			(size 0.19685 0.19685)
			(layers "F.Cu" "F.Mask" "F.Paste")
			(net "GND")
			(options
				(clearance outline)
				(anchor circle)
			)
			(primitives
				(gr_poly
					(pts
						(arc
							(start 0.508 -0.2921)
							(mid 0.478242 -0.363942)
							(end 0.4064 -0.3937)
						)
						(arc
							(start -0.4064 -0.3937)
							(mid -0.478242 -0.363942)
							(end -0.508 -0.2921)
						)
						(arc
							(start -0.508 0.2921)
							(mid -0.478242 0.363942)
							(end -0.4064 0.3937)
						)
						(arc
							(start 0.4064 0.3937)
							(mid 0.478242 0.363942)
							(end 0.508 0.2921)
						)
					)
					(width 0)
					(fill yes)
				)
			)
		)
	)
	(footprint ""
		(layer "F.Cu")
		(at 156.845 -45.339 90)
		(property "Reference" "R213"
			(at 0 0 90)
			(layer "F.SilkS")
			(hide yes)
			(effects
				(font
					(size 1.27 1.27)
				)
			)
		)
		(property "Value" "0R2J-2-GP"
			(at 1.7907 -1.1176 90)
			(unlocked yes)
			(layer "F.Fab")
			(hide yes)
			(effects
				(font
					(size 1.016 1.016)
					(thickness 0.1524)
				)
			)
		)
		(property "Device Type" "R402H16"
			(at 1.7907 -2.6416 90)
			(unlocked yes)
			(layer "F.Fab")
			(hide yes)
			(effects
				(font
					(size 1.016 1.016)
					(thickness 0.1524)
				)
			)
		)
		(duplicate_pad_numbers_are_jumpers no)
		(fp_rect
			(start -0.381 0.8382)
			(end 0.381 -0.8382)
			(stroke
				(width 0)
				(type default)
			)
			(fill no)
			(layer "F.CrtYd")
		)
		(fp_rect
			(start -0.381 0.8382)
			(end 0.381 -0.8382)
			(stroke
				(width 0)
				(type default)
			)
			(fill no)
			(layer "F.Fab")
		)
		(pad "1" smd custom
			(at 0 -0.4318 90)
			(size 0.127 0.127)
			(layers "F.Cu" "F.Mask" "F.Paste")
			(net "JTAG_CPU_PLD_TDO")
			(options
				(clearance outline)
				(anchor circle)
			)
			(primitives
				(gr_poly
					(pts
						(arc
							(start -0.2032 -0.2794)
							(mid -0.239121 -0.264521)
							(end -0.254 -0.2286)
						)
						(arc
							(start -0.254 0.2286)
							(mid -0.239121 0.264521)
							(end -0.2032 0.2794)
						)
						(arc
							(start 0.2032 0.2794)
							(mid 0.239121 0.264521)
							(end 0.254 0.2286)
						)
						(arc
							(start 0.254 -0.2286)
							(mid 0.239121 -0.264521)
							(end 0.2032 -0.2794)
						)
					)
					(width 0)
					(fill yes)
				)
			)
		)
		(pad "2" smd custom
			(at 0 0.4318 90)
			(size 0.127 0.127)
			(layers "F.Cu" "F.Mask" "F.Paste")
			(net "JTAG_CPU_PLD_TDO_D")
			(options
				(clearance outline)
				(anchor circle)
			)
			(primitives
				(gr_poly
					(pts
						(arc
							(start -0.2032 -0.2794)
							(mid -0.239121 -0.264521)
							(end -0.254 -0.2286)
						)
						(arc
							(start -0.254 0.2286)
							(mid -0.239121 0.264521)
							(end -0.2032 0.2794)
						)
						(arc
							(start 0.2032 0.2794)
							(mid 0.239121 0.264521)
							(end 0.254 0.2286)
						)
						(arc
							(start 0.254 -0.2286)
							(mid 0.239121 -0.264521)
							(end 0.2032 -0.2794)
						)
					)
					(width 0)
					(fill yes)
				)
			)
		)
	)
	(footprint ""
		(layer "F.Cu")
		(at 21.463 -58.42 90)
		(property "Reference" "PU3"
			(at 0 0 90)
			(layer "F.SilkS")
			(hide yes)
			(effects
				(font
					(size 1.27 1.27)
				)
			)
		)
		(property "Value" "ISL95831HRTZ-T-GP"
			(at 4.2164 1.2954 90)
			(unlocked yes)
			(layer "F.Fab")
			(hide yes)
			(effects
				(font
					(size 1.016 1.016)
					(thickness 0.1524)
				)
			)
		)
		(property "Device Type" "QFN48J6-G4D55H32"
			(at 4.2164 -0.2286 90)
			(unlocked yes)
			(layer "F.Fab")
			(hide yes)
			(effects
				(font
					(size 1.016 1.016)
					(thickness 0.1524)
				)
			)
		)
		(duplicate_pad_numbers_are_jumpers no)
		(fp_poly
			(pts
				(xy 2.180844 -3.38963) (xy 2.601214 -3.81) (xy 1.760474 -3.81)
			)
			(stroke
				(width 0)
				(type default)
			)
			(fill yes)
			(layer "F.SilkS")
		)
		(fp_rect
			(start -3.3782 3.3782)
			(end 3.3782 -3.3782)
			(stroke
				(width 0)
				(type default)
			)
			(fill no)
			(layer "F.CrtYd")
		)
		(fp_rect
			(start -3.3782 3.3782)
			(end 3.3782 -3.3782)
			(stroke
				(width 0)
				(type default)
			)
			(fill no)
			(layer "F.Fab")
		)
		(pad "1" smd rect
			(at 2.199894 -2.872994 90)
			(size 0.2032 0.762)
			(layers "F.Cu" "F.Mask" "F.Paste")
			(net "VR_PVNN_VW")
		)
		(pad "2" smd rect
			(at 1.800098 -2.872994 90)
			(size 0.2032 0.762)
			(layers "F.Cu" "F.Mask" "F.Paste")
			(net "VR_PVNN_IMON")
		)
		(pad "3" smd rect
			(at 1.400048 -2.872994 90)
			(size 0.2032 0.762)
			(layers "F.Cu" "F.Mask" "F.Paste")
			(net "PWRGD_R_PVNN")
		)
		(pad "4" smd rect
			(at 0.999998 -2.872994 90)
			(size 0.2032 0.762)
			(layers "F.Cu" "F.Mask" "F.Paste")
			(net "VR_95831_SDA")
		)
		(pad "5" smd rect
			(at 0.599948 -2.872994 90)
			(size 0.2032 0.762)
			(layers "F.Cu" "F.Mask" "F.Paste")
			(net "VR_95831_ALERT_N")
		)
		(pad "6" smd rect
			(at 0.199898 -2.872994 90)
			(size 0.2032 0.762)
			(layers "F.Cu" "F.Mask" "F.Paste")
			(net "VR_95831_SCLK")
		)
		(pad "7" smd rect
			(at -0.199898 -2.872994 90)
			(size 0.2032 0.762)
			(layers "F.Cu" "F.Mask" "F.Paste")
			(net "PVCC_PVNN_EN_R")
		)
		(pad "8" smd rect
			(at -0.599948 -2.872994 90)
			(size 0.2032 0.762)
			(layers "F.Cu" "F.Mask" "F.Paste")
			(net "PWRGD_R_PVCCP")
		)
		(pad "9" smd rect
			(at -0.999998 -2.872994 90)
			(size 0.2032 0.762)
			(layers "F.Cu" "F.Mask" "F.Paste")
			(net "VR_PVCCP_IMON")
		)
		(pad "10" smd rect
			(at -1.400048 -2.872994 90)
			(size 0.2032 0.762)
			(layers "F.Cu" "F.Mask" "F.Paste")
			(net "PVCCP_PVNN_R_VRHOT#")
		)
		(pad "11" smd rect
			(at -1.800098 -2.872994 90)
			(size 0.2032 0.762)
			(layers "F.Cu" "F.Mask" "F.Paste")
			(net "Net_315")
		)
		(pad "12" smd rect
			(at -2.199894 -2.872994 90)
			(size 0.2032 0.762)
			(layers "F.Cu" "F.Mask" "F.Paste")
			(net "VR_PVCCP_VW")
		)
		(pad "13" smd rect
			(at -2.872994 -2.199894 90)
			(size 0.762 0.2032)
			(layers "F.Cu" "F.Mask" "F.Paste")
			(net "VR_PVCCP_COMP")
		)
		(pad "14" smd rect
			(at -2.872994 -1.800098 90)
			(size 0.762 0.2032)
			(layers "F.Cu" "F.Mask" "F.Paste")
			(net "VR_PVCCP_FB")
		)
		(pad "15" smd rect
			(at -2.872994 -1.400048 90)
			(size 0.762 0.2032)
			(layers "F.Cu" "F.Mask" "F.Paste")
			(net "Net_322")
		)
		(pad "16" smd rect
			(at -2.872994 -0.999998 90)
			(size 0.762 0.2032)
			(layers "F.Cu" "F.Mask" "F.Paste")
			(net "PVCCP_ISEN2")
		)
		(pad "17" smd rect
			(at -2.872994 -0.599948 90)
			(size 0.762 0.2032)
			(layers "F.Cu" "F.Mask" "F.Paste")
			(net "VR_PVCCP_ISEN1_R")
		)
		(pad "18" smd rect
			(at -2.872994 -0.199898 90)
			(size 0.762 0.2032)
			(layers "F.Cu" "F.Mask" "F.Paste")
			(net "VR_PVCCP_VSEN")
		)
		(pad "19" smd rect
			(at -2.872994 0.199898 90)
			(size 0.762 0.2032)
			(layers "F.Cu" "F.Mask" "F.Paste")
			(net "VR_PVCCP_RTN")
		)
		(pad "20" smd rect
			(at -2.872994 0.599948 90)
			(size 0.762 0.2032)
			(layers "F.Cu" "F.Mask" "F.Paste")
			(net "VR_PVCCP_ISUMN_R")
		)
		(pad "21" smd rect
			(at -2.872994 0.999998 90)
			(size 0.762 0.2032)
			(layers "F.Cu" "F.Mask" "F.Paste")
			(net "VR_PVCCP_ISUMP")
		)
		(pad "22" smd rect
			(at -2.872994 1.400048 90)
			(size 0.762 0.2032)
			(layers "F.Cu" "F.Mask" "F.Paste")
			(net "VR_PVCCP_PVNN_VDD")
		)
		(pad "23" smd rect
			(at -2.872994 1.800098 90)
			(size 0.762 0.2032)
			(layers "F.Cu" "F.Mask" "F.Paste")
			(net "VR_PVCCP_PVNN_VIN")
		)
		(pad "24" smd rect
			(at -2.872994 2.199894 90)
			(size 0.762 0.2032)
			(layers "F.Cu" "F.Mask" "F.Paste")
			(net "VR_PVCCP_PROG1")
		)
		(pad "25" smd rect
			(at -2.199894 2.872994 90)
			(size 0.2032 0.762)
			(layers "F.Cu" "F.Mask" "F.Paste")
			(net "VR_PVCCP_BOOT")
		)
		(pad "26" smd rect
			(at -1.800098 2.872994 90)
			(size 0.2032 0.762)
			(layers "F.Cu" "F.Mask" "F.Paste")
			(net "VR_PVCCP_GH")
		)
		(pad "27" smd rect
			(at -1.400048 2.872994 90)
			(size 0.2032 0.762)
			(layers "F.Cu" "F.Mask" "F.Paste")
			(net "VR_PVCCP_PHASE")
		)
		(pad "28" smd rect
			(at -0.999998 2.872994 90)
			(size 0.2032 0.762)
			(layers "F.Cu" "F.Mask" "F.Paste")
			(net "GND")
		)
		(pad "29" smd rect
			(at -0.599948 2.872994 90)
			(size 0.2032 0.762)
			(layers "F.Cu" "F.Mask" "F.Paste")
			(net "VR_PVCCP_GL")
		)
		(pad "30" smd rect
			(at -0.199898 2.872994 90)
			(size 0.2032 0.762)
			(layers "F.Cu" "F.Mask" "F.Paste")
			(net "VR_PVCCP_PWM3")
		)
		(pad "31" smd rect
			(at 0.199898 2.872994 90)
			(size 0.2032 0.762)
			(layers "F.Cu" "F.Mask" "F.Paste")
			(net "VR_PVCCP_PVNN_VCCP")
		)
		(pad "32" smd rect
			(at 0.599948 2.872994 90)
			(size 0.2032 0.762)
			(layers "F.Cu" "F.Mask" "F.Paste")
			(net "Net_311")
		)
		(pad "33" smd rect
			(at 0.999998 2.872994 90)
			(size 0.2032 0.762)
			(layers "F.Cu" "F.Mask" "F.Paste")
			(net "GND")
		)
		(pad "34" smd rect
			(at 1.400048 2.872994 90)
			(size 0.2032 0.762)
			(layers "F.Cu" "F.Mask" "F.Paste")
			(net "Net_312")
		)
		(pad "35" smd rect
			(at 1.800098 2.872994 90)
			(size 0.2032 0.762)
			(layers "F.Cu" "F.Mask" "F.Paste")
			(net "Net_313")
		)
		(pad "36" smd rect
			(at 2.199894 2.872994 90)
			(size 0.2032 0.762)
			(layers "F.Cu" "F.Mask" "F.Paste")
			(net "Net_314")
		)
		(pad "37" smd rect
			(at 2.872994 2.199894 90)
			(size 0.762 0.2032)
			(layers "F.Cu" "F.Mask" "F.Paste")
			(net "VR_PVNN_GL")
		)
		(pad "38" smd rect
			(at 2.872994 1.800098 90)
			(size 0.762 0.2032)
			(layers "F.Cu" "F.Mask" "F.Paste")
			(net "VR_PVNN_PHASE")
		)
		(pad "39" smd rect
			(at 2.872994 1.400048 90)
			(size 0.762 0.2032)
			(layers "F.Cu" "F.Mask" "F.Paste")
			(net "VR_PVNN_GH")
		)
		(pad "40" smd rect
			(at 2.872994 0.999998 90)
			(size 0.762 0.2032)
			(layers "F.Cu" "F.Mask" "F.Paste")
			(net "VR_PVNN_BOOT")
		)
		(pad "41" smd rect
			(at 2.872994 0.599948 90)
			(size 0.762 0.2032)
			(layers "F.Cu" "F.Mask" "F.Paste")
			(net "VR_PVNN_PROG2")
		)
		(pad "42" smd rect
			(at 2.872994 0.199898 90)
			(size 0.762 0.2032)
			(layers "F.Cu" "F.Mask" "F.Paste")
			(net "VR_PVNN_NTC")
		)
		(pad "43" smd rect
			(at 2.872994 -0.199898 90)
			(size 0.762 0.2032)
			(layers "F.Cu" "F.Mask" "F.Paste")
			(net "VR_PVNN_ISUMN_R")
		)
		(pad "44" smd rect
			(at 2.872994 -0.599948 90)
			(size 0.762 0.2032)
			(layers "F.Cu" "F.Mask" "F.Paste")
			(net "VR_PVNN_ISUMP")
		)
		(pad "45" smd rect
			(at 2.872994 -0.999998 90)
			(size 0.762 0.2032)
			(layers "F.Cu" "F.Mask" "F.Paste")
			(net "VR_PVNN_RTN")
		)
		(pad "46" smd rect
			(at 2.872994 -1.400048 90)
			(size 0.762 0.2032)
			(layers "F.Cu" "F.Mask" "F.Paste")
			(net "VR_PVNN_VSEN")
		)
		(pad "47" smd rect
			(at 2.872994 -1.800098 90)
			(size 0.762 0.2032)
			(layers "F.Cu" "F.Mask" "F.Paste")
			(net "VR_PVNN_FB")
		)
		(pad "48" smd rect
			(at 2.872994 -2.199894 90)
			(size 0.762 0.2032)
			(layers "F.Cu" "F.Mask" "F.Paste")
			(net "VR_PVNN_COMP")
		)
		(pad "49" smd rect
			(at 0 0 90)
			(size 4.5466 4.5466)
			(layers "F.Cu" "F.Mask" "F.Paste")
			(net "GND")
		)
	)
)
